(kicad_pcb
	(version 20260206)
	(generator "pcbnew")
	(generator_version "10.0")
	(general
		(thickness 1.6)
		(legacy_teardrops no)
	)
	(paper "A4")
	(title_block
		(title "v2-tray-backplane — ms_tbp_v2.brd")
		(comment 1 "Open CloudServer (Microsoft) / footprint 52 of 164 (J13), pads 96-155 of 155")
	)
	(layers
		(0 "F.Cu" signal "TOP")
		(4 "In1.Cu" signal "LYR2")
		(6 "In2.Cu" signal "LYR3")
		(8 "In3.Cu" signal "LYR4")
		(10 "In4.Cu" signal "LYR5")
		(12 "In5.Cu" signal "LYR6")
		(14 "In6.Cu" signal "LYR7")
		(2 "B.Cu" signal "BOTTOM")
		(9 "F.Adhes" user "F.Adhesive")
		(11 "B.Adhes" user "B.Adhesive")
		(13 "F.Paste" user "Package Geometry/Pastemask Top")
		(15 "B.Paste" user "Package Geometry/Pastemask Bottom")
		(5 "F.SilkS" user "Ref Des/Silkscreen Top")
		(7 "B.SilkS" user "Ref Des/Silkscreen Bottom")
		(1 "F.Mask" user "Board Geometry/Soldermask Top")
		(3 "B.Mask" user "Board Geometry/Soldermask Bottom")
		(17 "Dwgs.User" user "User.Drawings")
		(19 "Cmts.User" user "User.Comments")
		(21 "Eco1.User" user "User.Eco1")
		(23 "Eco2.User" user "User.Eco2")
		(25 "Edge.Cuts" user "Board Geometry/Outline")
		(27 "Margin" user)
		(31 "F.CrtYd" user "Package Geometry/Place Bound Top")
		(29 "B.CrtYd" user "Package Geometry/Place Bound Bottom")
		(35 "F.Fab" user "Ref Des/Assembly Top")
		(33 "B.Fab" user "Ref Des/Assembly Bottom")
	)
	(footprint ""
		(layer "F.Cu")
		(at -171.46 45.260001 180)
		(property "Reference" "J13"
			(at 9.007 25.028901 0)
			(unlocked yes)
			(layer "F.SilkS")
			(effects
				(font
					(size 0.762 0.5334)
					(thickness 0.1016)
				)
			)
		)
		(property "Value" ""
			(at 0 0 180)
			(layer "F.Fab")
			(effects
				(font
					(size 1.27 1.27)
				)
			)
		)
		(duplicate_pad_numbers_are_jumpers no)
		(pad "J6" thru_hole circle
			(at 10 12.5 180)
			(size 0.8128 0.8128)
			(drill 0.508)
			(layers "*.Cu" "*.Mask")
			(remove_unused_layers no)
			(net "GND")
		)
		(pad "J7" thru_hole circle
			(at 11.999999 12.6 180)
			(size 0.8128 0.8128)
			(drill 0.508)
			(layers "*.Cu" "*.Mask")
			(remove_unused_layers no)
			(net "PCIE_B2T_B2_TX_DP<1>")
		)
		(pad "J8" thru_hole circle
			(at 14 12.5 180)
			(size 0.8128 0.8128)
			(drill 0.508)
			(layers "*.Cu" "*.Mask")
			(remove_unused_layers no)
			(net "GND")
		)
		(pad "J9" thru_hole circle
			(at 16.000001 12.6 180)
			(size 0.8128 0.8128)
			(drill 0.508)
			(layers "*.Cu" "*.Mask")
			(remove_unused_layers no)
			(net "CLK_100M_B2_P<3>")
		)
		(pad "J10" thru_hole circle
			(at 18 12.5 180)
			(size 0.8128 0.8128)
			(drill 0.508)
			(layers "*.Cu" "*.Mask")
			(remove_unused_layers no)
			(net "P12V_MEZZ_B2")
		)
		(pad "K1" thru_hole circle
			(at 0 14 180)
			(size 0.8128 0.8128)
			(drill 0.508)
			(layers "*.Cu" "*.Mask")
			(remove_unused_layers no)
			(net "PCIE_B2T_B2_TX_DN<7>")
		)
		(pad "K2" thru_hole circle
			(at 2.000001 13.9 180)
			(size 0.8128 0.8128)
			(drill 0.508)
			(layers "*.Cu" "*.Mask")
			(remove_unused_layers no)
			(net "PCIE_B2T_B2_TX_DP<6>")
		)
		(pad "K3" thru_hole circle
			(at 4 14 180)
			(size 0.8128 0.8128)
			(drill 0.508)
			(layers "*.Cu" "*.Mask")
			(remove_unused_layers no)
			(net "PCIE_B2T_B2_TX_DN<5>")
		)
		(pad "K4" thru_hole circle
			(at 6.000001 13.9 180)
			(size 0.8128 0.8128)
			(drill 0.508)
			(layers "*.Cu" "*.Mask")
			(remove_unused_layers no)
			(net "PCIE_B2T_B2_TX_DP<4>")
		)
		(pad "K5" thru_hole circle
			(at 7.999999 14 180)
			(size 0.8128 0.8128)
			(drill 0.508)
			(layers "*.Cu" "*.Mask")
			(remove_unused_layers no)
			(net "PCIE_B2T_B2_TX_DN<3>")
		)
		(pad "K6" thru_hole circle
			(at 10 13.9 180)
			(size 0.8128 0.8128)
			(drill 0.508)
			(layers "*.Cu" "*.Mask")
			(remove_unused_layers no)
			(net "PCIE_B2T_B2_TX_DP<2>")
		)
		(pad "K7" thru_hole circle
			(at 11.999999 14 180)
			(size 0.8128 0.8128)
			(drill 0.508)
			(layers "*.Cu" "*.Mask")
			(remove_unused_layers no)
			(net "PCIE_B2T_B2_TX_DN<1>")
		)
		(pad "K8" thru_hole circle
			(at 14 13.9 180)
			(size 0.8128 0.8128)
			(drill 0.508)
			(layers "*.Cu" "*.Mask")
			(remove_unused_layers no)
			(net "PCIE_B2T_B2_TX_DP<0>")
		)
		(pad "K9" thru_hole circle
			(at 16.000001 14 180)
			(size 0.8128 0.8128)
			(drill 0.508)
			(layers "*.Cu" "*.Mask")
			(remove_unused_layers no)
			(net "CLK_100M_B2_N<3>")
		)
		(pad "K10" thru_hole circle
			(at 18 13.9 180)
			(size 0.8128 0.8128)
			(drill 0.508)
			(layers "*.Cu" "*.Mask")
			(remove_unused_layers no)
			(net "P12V_MEZZ_B2")
		)
		(pad "L1" thru_hole circle
			(at 0 15.4 180)
			(size 0.8128 0.8128)
			(drill 0.508)
			(layers "*.Cu" "*.Mask")
			(remove_unused_layers no)
			(net "GND")
		)
		(pad "L2" thru_hole circle
			(at 2.000001 15.3 180)
			(size 0.8128 0.8128)
			(drill 0.508)
			(layers "*.Cu" "*.Mask")
			(remove_unused_layers no)
			(net "PCIE_B2T_B2_TX_DN<6>")
		)
		(pad "L3" thru_hole circle
			(at 4 15.4 180)
			(size 0.8128 0.8128)
			(drill 0.508)
			(layers "*.Cu" "*.Mask")
			(remove_unused_layers no)
			(net "GND")
		)
		(pad "L4" thru_hole circle
			(at 6.000001 15.3 180)
			(size 0.8128 0.8128)
			(drill 0.508)
			(layers "*.Cu" "*.Mask")
			(remove_unused_layers no)
			(net "PCIE_B2T_B2_TX_DN<4>")
		)
		(pad "L5" thru_hole circle
			(at 7.999999 15.4 180)
			(size 0.8128 0.8128)
			(drill 0.508)
			(layers "*.Cu" "*.Mask")
			(remove_unused_layers no)
			(net "GND")
		)
		(pad "L6" thru_hole circle
			(at 10 15.3 180)
			(size 0.8128 0.8128)
			(drill 0.508)
			(layers "*.Cu" "*.Mask")
			(remove_unused_layers no)
			(net "PCIE_B2T_B2_TX_DN<2>")
		)
		(pad "L7" thru_hole circle
			(at 11.999999 15.4 180)
			(size 0.8128 0.8128)
			(drill 0.508)
			(layers "*.Cu" "*.Mask")
			(remove_unused_layers no)
			(net "GND")
		)
		(pad "L8" thru_hole circle
			(at 14 15.3 180)
			(size 0.8128 0.8128)
			(drill 0.508)
			(layers "*.Cu" "*.Mask")
			(remove_unused_layers no)
			(net "PCIE_B2T_B2_TX_DN<0>")
		)
		(pad "L9" thru_hole circle
			(at 16.000001 15.4 180)
			(size 0.8128 0.8128)
			(drill 0.508)
			(layers "*.Cu" "*.Mask")
			(remove_unused_layers no)
			(net "GND")
		)
		(pad "L10" thru_hole circle
			(at 18 15.3 180)
			(size 0.8128 0.8128)
			(drill 0.508)
			(layers "*.Cu" "*.Mask")
			(remove_unused_layers no)
			(net "P12V_MEZZ_B2")
		)
		(pad "M1" thru_hole circle
			(at 0 16.799999 180)
			(size 0.8128 0.8128)
			(drill 0.508)
			(layers "*.Cu" "*.Mask")
			(remove_unused_layers no)
			(net "PCIE_B2T_B2_TX_DP<15>")
		)
		(pad "M2" thru_hole circle
			(at 2.000001 16.7 180)
			(size 0.8128 0.8128)
			(drill 0.508)
			(layers "*.Cu" "*.Mask")
			(remove_unused_layers no)
			(net "GND")
		)
		(pad "M3" thru_hole circle
			(at 4 16.799999 180)
			(size 0.8128 0.8128)
			(drill 0.508)
			(layers "*.Cu" "*.Mask")
			(remove_unused_layers no)
			(net "PCIE_B2T_B2_TX_DP<13>")
		)
		(pad "M4" thru_hole circle
			(at 6.000001 16.7 180)
			(size 0.8128 0.8128)
			(drill 0.508)
			(layers "*.Cu" "*.Mask")
			(remove_unused_layers no)
			(net "GND")
		)
		(pad "M5" thru_hole circle
			(at 7.999999 16.799999 180)
			(size 0.8128 0.8128)
			(drill 0.508)
			(layers "*.Cu" "*.Mask")
			(remove_unused_layers no)
			(net "PCIE_B2T_B2_TX_DP<11>")
		)
		(pad "M6" thru_hole circle
			(at 10 16.7 180)
			(size 0.8128 0.8128)
			(drill 0.508)
			(layers "*.Cu" "*.Mask")
			(remove_unused_layers no)
			(net "GND")
		)
		(pad "M7" thru_hole circle
			(at 11.999999 16.799999 180)
			(size 0.8128 0.8128)
			(drill 0.508)
			(layers "*.Cu" "*.Mask")
			(remove_unused_layers no)
			(net "PCIE_B2T_B2_TX_DP<9>")
		)
		(pad "M8" thru_hole circle
			(at 14 16.7 180)
			(size 0.8128 0.8128)
			(drill 0.508)
			(layers "*.Cu" "*.Mask")
			(remove_unused_layers no)
			(net "GND")
		)
		(pad "M9" thru_hole circle
			(at 16.000001 16.799999 180)
			(size 0.8128 0.8128)
			(drill 0.508)
			(layers "*.Cu" "*.Mask")
			(remove_unused_layers no)
			(net "GND")
		)
		(pad "M10" thru_hole circle
			(at 18 16.7 180)
			(size 0.8128 0.8128)
			(drill 0.508)
			(layers "*.Cu" "*.Mask")
			(remove_unused_layers no)
			(net "GND")
		)
		(pad "N1" thru_hole circle
			(at 0 18.199999 180)
			(size 0.8128 0.8128)
			(drill 0.508)
			(layers "*.Cu" "*.Mask")
			(remove_unused_layers no)
			(net "PCIE_B2T_B2_TX_DN<15>")
		)
		(pad "N2" thru_hole circle
			(at 2.000001 18.099999 180)
			(size 0.8128 0.8128)
			(drill 0.508)
			(layers "*.Cu" "*.Mask")
			(remove_unused_layers no)
			(net "PCIE_B2T_B2_TX_DP<14>")
		)
		(pad "N3" thru_hole circle
			(at 4 18.199999 180)
			(size 0.8128 0.8128)
			(drill 0.508)
			(layers "*.Cu" "*.Mask")
			(remove_unused_layers no)
			(net "PCIE_B2T_B2_TX_DN<13>")
		)
		(pad "N4" thru_hole circle
			(at 6.000001 18.099999 180)
			(size 0.8128 0.8128)
			(drill 0.508)
			(layers "*.Cu" "*.Mask")
			(remove_unused_layers no)
			(net "PCIE_B2T_B2_TX_DP<12>")
		)
		(pad "N5" thru_hole circle
			(at 7.999999 18.199999 180)
			(size 0.8128 0.8128)
			(drill 0.508)
			(layers "*.Cu" "*.Mask")
			(remove_unused_layers no)
			(net "PCIE_B2T_B2_TX_DN<11>")
		)
		(pad "N6" thru_hole circle
			(at 10 18.099999 180)
			(size 0.8128 0.8128)
			(drill 0.508)
			(layers "*.Cu" "*.Mask")
			(remove_unused_layers no)
			(net "PCIE_B2T_B2_TX_DP<10>")
		)
		(pad "N7" thru_hole circle
			(at 11.999999 18.199999 180)
			(size 0.8128 0.8128)
			(drill 0.508)
			(layers "*.Cu" "*.Mask")
			(remove_unused_layers no)
			(net "PCIE_B2T_B2_TX_DN<9>")
		)
		(pad "N8" thru_hole circle
			(at 14 18.099999 180)
			(size 0.8128 0.8128)
			(drill 0.508)
			(layers "*.Cu" "*.Mask")
			(remove_unused_layers no)
			(net "PCIE_B2T_B2_TX_DP<8>")
		)
		(pad "N9" thru_hole circle
			(at 16.000001 18.199999 180)
			(size 0.8128 0.8128)
			(drill 0.508)
			(layers "*.Cu" "*.Mask")
			(remove_unused_layers no)
			(net "GND")
		)
		(pad "N10" thru_hole circle
			(at 18 18.099999 180)
			(size 0.8128 0.8128)
			(drill 0.508)
			(layers "*.Cu" "*.Mask")
			(remove_unused_layers no)
			(net "P12V_MEZZ_B2")
		)
		(pad "O1" thru_hole circle
			(at 0 19.599999 180)
			(size 0.8128 0.8128)
			(drill 0.508)
			(layers "*.Cu" "*.Mask")
			(remove_unused_layers no)
			(net "GND")
		)
		(pad "O2" thru_hole circle
			(at 2.000001 19.499999 180)
			(size 0.8128 0.8128)
			(drill 0.508)
			(layers "*.Cu" "*.Mask")
			(remove_unused_layers no)
			(net "PCIE_B2T_B2_TX_DN<14>")
		)
		(pad "O3" thru_hole circle
			(at 4 19.599999 180)
			(size 0.8128 0.8128)
			(drill 0.508)
			(layers "*.Cu" "*.Mask")
			(remove_unused_layers no)
			(net "GND")
		)
		(pad "O4" thru_hole circle
			(at 6.000001 19.499999 180)
			(size 0.8128 0.8128)
			(drill 0.508)
			(layers "*.Cu" "*.Mask")
			(remove_unused_layers no)
			(net "PCIE_B2T_B2_TX_DN<12>")
		)
		(pad "O5" thru_hole circle
			(at 7.999999 19.599999 180)
			(size 0.8128 0.8128)
			(drill 0.508)
			(layers "*.Cu" "*.Mask")
			(remove_unused_layers no)
			(net "GND")
		)
		(pad "O6" thru_hole circle
			(at 10 19.499999 180)
			(size 0.8128 0.8128)
			(drill 0.508)
			(layers "*.Cu" "*.Mask")
			(remove_unused_layers no)
			(net "PCIE_B2T_B2_TX_DN<10>")
		)
		(pad "O7" thru_hole circle
			(at 11.999999 19.599999 180)
			(size 0.8128 0.8128)
			(drill 0.508)
			(layers "*.Cu" "*.Mask")
			(remove_unused_layers no)
			(net "GND")
		)
		(pad "O8" thru_hole circle
			(at 14 19.499999 180)
			(size 0.8128 0.8128)
			(drill 0.508)
			(layers "*.Cu" "*.Mask")
			(remove_unused_layers no)
			(net "PCIE_B2T_B2_TX_DN<8>")
		)
		(pad "O9" thru_hole circle
			(at 16.000001 19.599999 180)
			(size 0.8128 0.8128)
			(drill 0.508)
			(layers "*.Cu" "*.Mask")
			(remove_unused_layers no)
			(net "GND")
		)
		(pad "O10" thru_hole circle
			(at 18 19.499999 180)
			(size 0.8128 0.8128)
			(drill 0.508)
			(layers "*.Cu" "*.Mask")
			(remove_unused_layers no)
			(net "P12V_MEZZ_B2")
		)
		(pad "P2" thru_hole circle
			(at 2.000001 20.899999 180)
			(size 0.8128 0.8128)
			(drill 0.508)
			(layers "*.Cu" "*.Mask")
			(remove_unused_layers no)
			(net "GND")
		)
		(pad "P4" thru_hole circle
			(at 6.000001 20.899999 180)
			(size 0.8128 0.8128)
			(drill 0.508)
			(layers "*.Cu" "*.Mask")
			(remove_unused_layers no)
			(net "GND")
		)
		(pad "P6" thru_hole circle
			(at 10 20.899999 180)
			(size 0.8128 0.8128)
			(drill 0.508)
			(layers "*.Cu" "*.Mask")
			(remove_unused_layers no)
			(net "GND")
		)
		(pad "P8" thru_hole circle
			(at 14 20.899999 180)
			(size 0.8128 0.8128)
			(drill 0.508)
			(layers "*.Cu" "*.Mask")
			(remove_unused_layers no)
			(net "GND")
		)
		(pad "P10" thru_hole circle
			(at 18 20.899999 180)
			(size 0.8128 0.8128)
			(drill 0.508)
			(layers "*.Cu" "*.Mask")
			(remove_unused_layers no)
			(net "GND")
		)
	)
)
